FILE_TYPE = MACRO_DRAWING;
SET COLOR_WIRE YELLOW;
SET COLOR_PROP MONO;
SET COLOR_DOT WHITE;
SET COLOR_ARC YELLOW;
SET COLOR_BODY GREEN;
SET COLOR_NOTE MONO;
SET PROP_DISPLAY VALUE;
SET PAGE_NUMBER P2;
FORCEADD INTEL_CORP_BPAGE..3
(0 0);
FORCEPROP 1 LAST CDS_CON_LAST_MODIFIED Fri Jun 16 17:47:55 2017
J 0
(-1425 325);
PAINT ORANGE (-1425 325);
DISPLAY INVISIBLE (-1425 325);
FORCEPROP 2 LAST CUSTOM_TXT_CDS <XR_PAGE_TITLE>
J 0
(-7890 5250);
DISPLAY 0.638298 (-7890 5250);
PAINT PINK (-7890 5250);
DISPLAY INVISIBLE (-7890 5250);
FORCEPROP 2 LAST CUSTOM_TXT_CDS <CON_TC_SNM11>
J 0
(-7050 3525);
PAINT ORANGE (-7050 3525);
FORCEPROP 2 LAST CUSTOM_TXT_CDS <CON_TC_SNM9>
J 0
(-7050 3725);
PAINT ORANGE (-7050 3725);
FORCEPROP 2 LAST CUSTOM_TXT_CDS <CON_TC_SNM5>
J 0
(-7050 4125);
PAINT ORANGE (-7050 4125);
FORCEPROP 2 LAST CUSTOM_TXT_CDS <CON_TC_SNM92>
J 0
(-2050 3425);
PAINT ORANGE (-2050 3425);
FORCEPROP 2 LAST CUSTOM_TXT_CDS <CON_TC_SNM35>
J 0
(-7050 1125);
PAINT ORANGE (-7050 1125);
FORCEPROP 2 LAST CUSTOM_TXT_CDS <CON_TC_SNM2>
J 0
(-7050 4425);
PAINT ORANGE (-7050 4425);
FORCEPROP 2 LAST CUSTOM_TXT_CDS <CON_TC_SNM56>
J 0
(-4550 3025);
PAINT ORANGE (-4550 3025);
FORCEPROP 2 LAST CUSTOM_TXT_CDS <CON_TC_SNM109>
J 0
(-2050 1725);
PAINT ORANGE (-2050 1725);
FORCEPROP 2 LAST CUSTOM_TXT_CDS <CON_TC_SNO19>
J 2
(-7150 2725);
PAINT ORANGE (-7150 2725);
FORCEPROP 2 LAST CUSTOM_TXT_CDS <CON_TC_SNM41>
J 0
(-4550 4525);
PAINT ORANGE (-4550 4525);
FORCEPROP 2 LAST CUSTOM_TXT_CDS <CON_TC_SNM49>
J 0
(-4550 3725);
PAINT ORANGE (-4550 3725);
FORCEPROP 2 LAST CUSTOM_TXT_CDS <CON_TC_SNM105>
J 0
(-2050 2125);
PAINT ORANGE (-2050 2125);
FORCEPROP 2 LAST CUSTOM_TXT_CDS <CON_TC_SNM63>
J 0
(-4550 2325);
PAINT ORANGE (-4550 2325);
FORCEPROP 2 LAST CUSTOM_TXT_CDS <CON_TC_SNM51>
J 0
(-4550 3525);
PAINT ORANGE (-4550 3525);
FORCEPROP 2 LAST CUSTOM_TXT_CDS <CON_TC_SNM6>
J 0
(-7050 4025);
PAINT ORANGE (-7050 4025);
FORCEPROP 2 LAST CUSTOM_TXT_CDS <CON_TC_SNM98>
J 0
(-2050 2825);
PAINT ORANGE (-2050 2825);
FORCEPROP 2 LAST CUSTOM_TXT_CDS <CON_TC_SNM50>
J 0
(-4550 3625);
PAINT ORANGE (-4550 3625);
FORCEPROP 2 LAST CUSTOM_TXT_CDS <CON_TC_SNM44>
J 0
(-4550 4225);
PAINT ORANGE (-4550 4225);
FORCEPROP 2 LAST CUSTOM_TXT_CDS <CON_TC_SNM4>
J 0
(-7050 4225);
PAINT ORANGE (-7050 4225);
FORCEPROP 2 LAST CUSTOM_TXT_CDS <CON_TC_SNM104>
J 0
(-2050 2225);
PAINT ORANGE (-2050 2225);
FORCEPROP 2 LAST CUSTOM_TXT_CDS <CON_TC_SNM48>
J 0
(-4550 3825);
PAINT ORANGE (-4550 3825);
FORCEPROP 2 LAST CUSTOM_TXT_CDS <CON_TC_SNM84>
J 0
(-2050 4225);
PAINT ORANGE (-2050 4225);
FORCEPROP 2 LAST CUSTOM_TXT_CDS <CON_TC_SNM15>
J 0
(-7050 3125);
PAINT ORANGE (-7050 3125);
FORCEPROP 2 LAST CUSTOM_TXT_CDS <CON_TC_SNM10>
J 0
(-7050 3625);
PAINT ORANGE (-7050 3625);
FORCEPROP 2 LAST CUSTOM_TXT_CDS <CON_TC_SNM13>
J 0
(-7050 3325);
PAINT ORANGE (-7050 3325);
FORCEPROP 2 LAST CUSTOM_TXT_CDS <CON_TC_SNM1>
J 0
(-7050 4525);
PAINT ORANGE (-7050 4525);
FORCEPROP 2 LAST CUSTOM_TXT_CDS <CON_TC_SNM8>
J 0
(-7050 3825);
PAINT ORANGE (-7050 3825);
FORCEPROP 2 LAST CUSTOM_TXT_CDS <CON_TC_SNM12>
J 0
(-7050 3425);
PAINT ORANGE (-7050 3425);
FORCEPROP 2 LAST CUSTOM_TXT_CDS <CON_TC_SNM14>
J 0
(-7050 3225);
PAINT ORANGE (-7050 3225);
FORCEPROP 2 LAST CUSTOM_TXT_CDS <CON_TC_SNM16>
J 0
(-7050 3025);
PAINT ORANGE (-7050 3025);
FORCEPROP 2 LAST CUSTOM_TXT_CDS <CON_TC_SNM17>
J 0
(-7050 2925);
PAINT ORANGE (-7050 2925);
FORCEPROP 2 LAST CUSTOM_TXT_CDS <CON_TC_SNM18>
J 0
(-7050 2825);
PAINT ORANGE (-7050 2825);
FORCEPROP 2 LAST CUSTOM_TXT_CDS <CON_TC_SNO1>
J 2
(-7150 4525);
PAINT ORANGE (-7150 4525);
FORCEPROP 2 LAST CUSTOM_TXT_CDS <CON_TC_SNO2>
J 2
(-7150 4425);
PAINT ORANGE (-7150 4425);
FORCEPROP 2 LAST CUSTOM_TXT_CDS <CON_TC_SNO3>
J 2
(-7150 4325);
PAINT ORANGE (-7150 4325);
FORCEPROP 2 LAST CUSTOM_TXT_CDS <CON_TC_SNO4>
J 2
(-7150 4225);
PAINT ORANGE (-7150 4225);
FORCEPROP 2 LAST CUSTOM_TXT_CDS <CON_TC_SNO5>
J 2
(-7150 4125);
PAINT ORANGE (-7150 4125);
FORCEPROP 2 LAST CUSTOM_TXT_CDS <CON_TC_SNO6>
J 2
(-7150 4025);
PAINT ORANGE (-7150 4025);
FORCEPROP 2 LAST CUSTOM_TXT_CDS <CON_TC_SNO7>
J 2
(-7150 3925);
PAINT ORANGE (-7150 3925);
FORCEPROP 2 LAST CUSTOM_TXT_CDS <CON_TC_SNO8>
J 2
(-7150 3825);
PAINT ORANGE (-7150 3825);
FORCEPROP 2 LAST CUSTOM_TXT_CDS <CON_TC_SNO9>
J 2
(-7150 3725);
PAINT ORANGE (-7150 3725);
FORCEPROP 2 LAST CUSTOM_TXT_CDS <CON_TC_SNO10>
J 2
(-7150 3625);
PAINT ORANGE (-7150 3625);
FORCEPROP 2 LAST CUSTOM_TXT_CDS <CON_TC_SNO12>
J 2
(-7150 3425);
PAINT ORANGE (-7150 3425);
FORCEPROP 2 LAST CUSTOM_TXT_CDS <CON_TC_SNO13>
J 2
(-7150 3325);
PAINT ORANGE (-7150 3325);
FORCEPROP 2 LAST CUSTOM_TXT_CDS <CON_TC_SNO14>
J 2
(-7150 3225);
PAINT ORANGE (-7150 3225);
FORCEPROP 2 LAST CUSTOM_TXT_CDS <CON_TC_SNO15>
J 2
(-7150 3125);
PAINT ORANGE (-7150 3125);
FORCEPROP 2 LAST CUSTOM_TXT_CDS <CON_TC_SNO16>
J 2
(-7150 3025);
PAINT ORANGE (-7150 3025);
FORCEPROP 2 LAST CUSTOM_TXT_CDS <CON_TC_SNO17>
J 2
(-7150 2925);
PAINT ORANGE (-7150 2925);
FORCEPROP 2 LAST CUSTOM_TXT_CDS <CON_TC_SNO18>
J 2
(-7150 2825);
PAINT ORANGE (-7150 2825);
FORCEPROP 2 LAST CUSTOM_TXT_CDS <CON_TC_SNO11>
J 2
(-7150 3525);
PAINT ORANGE (-7150 3525);
FORCEPROP 2 LAST CUSTOM_TXT_CDS <CON_TC_SNM7>
J 0
(-7050 3925);
PAINT ORANGE (-7050 3925);
FORCEPROP 2 LAST CUSTOM_TXT_CDS <CON_TC_SNM3>
J 0
(-7050 4325);
PAINT ORANGE (-7050 4325);
FORCEPROP 2 LAST CUSTOM_TXT_CDS <CON_TC_SNM120>
J 0
(-2050 625);
PAINT ORANGE (-2050 625);
FORCEPROP 2 LAST CUSTOM_TXT_CDS <CON_TC_SNO120>
J 2
(-2150 625);
PAINT ORANGE (-2150 625);
FORCEPROP 2 LAST CUSTOM_TXT_CDS <CON_LAST_MODIFIED>
J 0
(-4000 100);
PAINT ORANGE (-4000 100);
FORCEPROP 2 LAST CUSTOM_TXT_CDS <CON_TC_SNM119>
J 0
(-2050 725);
PAINT ORANGE (-2050 725);
FORCEPROP 2 LAST CUSTOM_TXT_CDS <CON_TC_SNM75>
J 0
(-4550 1125);
PAINT ORANGE (-4550 1125);
FORCEPROP 2 LAST CUSTOM_TXT_CDS <CURRENT_DESIGN_SHEET> OF <TOTAL_DESIGN_SHEETS>
J 0
(-500 25);
PAINT ORANGE (-500 25);
FORCEPROP 2 LAST CUSTOM_TXT_CDS <CON_TC_SNM99>
J 0
(-2050 2725);
PAINT ORANGE (-2050 2725);
FORCEPROP 2 LAST CUSTOM_TXT_CDS <CON_TC_SNM95>
J 0
(-2050 3125);
PAINT ORANGE (-2050 3125);
FORCEPROP 2 LAST CUSTOM_TXT_CDS <CON_TC_SNM94>
J 0
(-2050 3225);
PAINT ORANGE (-2050 3225);
FORCEPROP 2 LAST CUSTOM_TXT_CDS <CON_TC_SNM91>
J 0
(-2050 3525);
PAINT ORANGE (-2050 3525);
FORCEPROP 2 LAST CUSTOM_TXT_CDS <CON_TC_SNM90>
J 0
(-2050 3625);
PAINT ORANGE (-2050 3625);
FORCEPROP 2 LAST CUSTOM_TXT_CDS <CON_TC_SNM86>
J 0
(-2050 4025);
PAINT ORANGE (-2050 4025);
FORCEPROP 2 LAST CUSTOM_TXT_CDS <CON_TC_SNO118>
J 2
(-2150 825);
PAINT ORANGE (-2150 825);
FORCEPROP 2 LAST CUSTOM_TXT_CDS <CON_TC_SNM118>
J 0
(-2050 825);
PAINT ORANGE (-2050 825);
FORCEPROP 2 LAST CUSTOM_TXT_CDS <CON_TC_SNM117>
J 0
(-2050 925);
PAINT ORANGE (-2050 925);
FORCEPROP 2 LAST CUSTOM_TXT_CDS <CON_TC_SNM80>
J 0
(-4550 625);
PAINT ORANGE (-4550 625);
FORCEPROP 2 LAST CUSTOM_TXT_CDS <CON_TC_SNM23>
J 0
(-7050 2325);
PAINT ORANGE (-7050 2325);
FORCEPROP 2 LAST CUSTOM_TXT_CDS <CON_TC_SNM55>
J 0
(-4550 3125);
PAINT ORANGE (-4550 3125);
FORCEPROP 2 LAST CUSTOM_TXT_CDS <CON_TC_SNM19>
J 0
(-7050 2725);
PAINT ORANGE (-7050 2725);
FORCEPROP 2 LAST CUSTOM_TXT_CDS <CON_TC_SNO68>
J 2
(-4650 1825);
PAINT ORANGE (-4650 1825);
FORCEPROP 2 LAST CUSTOM_TXT_CDS <CON_TC_SNM67>
J 0
(-4550 1925);
PAINT ORANGE (-4550 1925);
FORCEPROP 2 LAST CUSTOM_TXT_CDS <CON_TC_SNM66>
J 0
(-4550 2025);
PAINT ORANGE (-4550 2025);
FORCEPROP 2 LAST CUSTOM_TXT_CDS <CON_TC_SNM65>
J 0
(-4550 2125);
PAINT ORANGE (-4550 2125);
FORCEPROP 2 LAST CUSTOM_TXT_CDS <CON_TC_SNM64>
J 0
(-4550 2225);
PAINT ORANGE (-4550 2225);
FORCEPROP 2 LAST CUSTOM_TXT_CDS <CON_TC_SNM62>
J 0
(-4550 2425);
PAINT ORANGE (-4550 2425);
FORCEPROP 2 LAST CUSTOM_TXT_CDS <CON_TC_SNM61>
J 0
(-4550 2525);
PAINT ORANGE (-4550 2525);
FORCEPROP 2 LAST CUSTOM_TXT_CDS <CON_TC_SNM60>
J 0
(-4550 2625);
PAINT ORANGE (-4550 2625);
FORCEPROP 2 LAST CUSTOM_TXT_CDS <CON_TC_SNM59>
J 0
(-4550 2725);
PAINT ORANGE (-4550 2725);
FORCEPROP 2 LAST CUSTOM_TXT_CDS <CON_TC_SNM57>
J 0
(-4550 2925);
PAINT ORANGE (-4550 2925);
FORCEPROP 2 LAST CUSTOM_TXT_CDS <CON_TC_SNM52>
J 0
(-4550 3425);
PAINT ORANGE (-4550 3425);
FORCEPROP 2 LAST CUSTOM_TXT_CDS <CON_TC_SNO48>
J 2
(-4650 3825);
PAINT ORANGE (-4650 3825);
FORCEPROP 2 LAST CUSTOM_TXT_CDS <CON_TC_SNO52>
J 2
(-4650 3425);
PAINT ORANGE (-4650 3425);
FORCEPROP 2 LAST CUSTOM_TXT_CDS <CON_TC_SNM68>
J 0
(-4550 1825);
PAINT ORANGE (-4550 1825);
FORCEPROP 2 LAST CUSTOM_TXT_CDS <CON_TC_SNO71>
J 2
(-4650 1525);
PAINT ORANGE (-4650 1525);
FORCEPROP 2 LAST CUSTOM_TXT_CDS <CON_TC_SNM40>
J 0
(-7050 625);
PAINT ORANGE (-7050 625);
FORCEPROP 2 LAST CUSTOM_TXT_CDS <CON_TC_SNM20>
J 0
(-7050 2625);
PAINT ORANGE (-7050 2625);
FORCEPROP 2 LAST CUSTOM_TXT_CDS <CON_TC_SNM21>
J 0
(-7050 2525);
PAINT ORANGE (-7050 2525);
FORCEPROP 2 LAST CUSTOM_TXT_CDS <CON_TC_SNM22>
J 0
(-7050 2425);
PAINT ORANGE (-7050 2425);
FORCEPROP 2 LAST CUSTOM_TXT_CDS <CON_TC_SNM24>
J 0
(-7050 2225);
PAINT ORANGE (-7050 2225);
FORCEPROP 2 LAST CUSTOM_TXT_CDS <CON_TC_SNM25>
J 0
(-7050 2125);
PAINT ORANGE (-7050 2125);
FORCEPROP 2 LAST CUSTOM_TXT_CDS <CON_TC_SNM26>
J 0
(-7050 2025);
PAINT ORANGE (-7050 2025);
FORCEPROP 2 LAST CUSTOM_TXT_CDS <CON_TC_SNM27>
J 0
(-7050 1925);
PAINT ORANGE (-7050 1925);
FORCEPROP 2 LAST CUSTOM_TXT_CDS <CON_TC_SNM28>
J 0
(-7050 1825);
PAINT ORANGE (-7050 1825);
FORCEPROP 2 LAST CUSTOM_TXT_CDS <CON_TC_SNM29>
J 0
(-7050 1725);
PAINT ORANGE (-7050 1725);
FORCEPROP 2 LAST CUSTOM_TXT_CDS <CON_TC_SNM30>
J 0
(-7050 1625);
PAINT ORANGE (-7050 1625);
FORCEPROP 2 LAST CUSTOM_TXT_CDS <CON_TC_SNM31>
J 0
(-7050 1525);
PAINT ORANGE (-7050 1525);
FORCEPROP 2 LAST CUSTOM_TXT_CDS <CON_TC_SNM33>
J 0
(-7050 1325);
PAINT ORANGE (-7050 1325);
FORCEPROP 2 LAST CUSTOM_TXT_CDS <CON_TC_SNM34>
J 0
(-7050 1225);
PAINT ORANGE (-7050 1225);
FORCEPROP 2 LAST CUSTOM_TXT_CDS <CON_TC_SNM36>
J 0
(-7050 1025);
PAINT ORANGE (-7050 1025);
FORCEPROP 2 LAST CUSTOM_TXT_CDS <CON_TC_SNM37>
J 0
(-7050 925);
PAINT ORANGE (-7050 925);
FORCEPROP 2 LAST CUSTOM_TXT_CDS <CON_TC_SNM38>
J 0
(-7050 825);
PAINT ORANGE (-7050 825);
FORCEPROP 2 LAST CUSTOM_TXT_CDS <CON_TC_SNM39>
J 0
(-7050 725);
PAINT ORANGE (-7050 725);
FORCEPROP 2 LAST CUSTOM_TXT_CDS <CON_TC_SNM45>
J 0
(-4550 4125);
PAINT ORANGE (-4550 4125);
FORCEPROP 2 LAST CUSTOM_TXT_CDS <CON_TC_SNM46>
J 0
(-4550 4025);
PAINT ORANGE (-4550 4025);
FORCEPROP 2 LAST CUSTOM_TXT_CDS <CON_TC_SNM47>
J 0
(-4550 3925);
PAINT ORANGE (-4550 3925);
FORCEPROP 2 LAST CUSTOM_TXT_CDS <CON_TC_SNM53>
J 0
(-4550 3325);
PAINT ORANGE (-4550 3325);
FORCEPROP 2 LAST CUSTOM_TXT_CDS <CON_TC_SNM54>
J 0
(-4550 3225);
PAINT ORANGE (-4550 3225);
FORCEPROP 2 LAST CUSTOM_TXT_CDS <CON_TC_SNM58>
J 0
(-4550 2825);
PAINT ORANGE (-4550 2825);
FORCEPROP 2 LAST CUSTOM_TXT_CDS <CON_TC_SNM69>
J 0
(-4550 1725);
PAINT ORANGE (-4550 1725);
FORCEPROP 2 LAST CUSTOM_TXT_CDS <CON_TC_SNM70>
J 0
(-4550 1625);
PAINT ORANGE (-4550 1625);
FORCEPROP 2 LAST CUSTOM_TXT_CDS <CON_TC_SNM71>
J 0
(-4550 1525);
PAINT ORANGE (-4550 1525);
FORCEPROP 2 LAST CUSTOM_TXT_CDS <CON_TC_SNM72>
J 0
(-4550 1425);
PAINT ORANGE (-4550 1425);
FORCEPROP 2 LAST CUSTOM_TXT_CDS <CON_TC_SNM73>
J 0
(-4550 1325);
PAINT ORANGE (-4550 1325);
FORCEPROP 2 LAST CUSTOM_TXT_CDS <CON_TC_SNM74>
J 0
(-4550 1225);
PAINT ORANGE (-4550 1225);
FORCEPROP 2 LAST CUSTOM_TXT_CDS <CON_TC_SNM76>
J 0
(-4550 1025);
PAINT ORANGE (-4550 1025);
FORCEPROP 2 LAST CUSTOM_TXT_CDS <CON_TC_SNM77>
J 0
(-4550 925);
PAINT ORANGE (-4550 925);
FORCEPROP 2 LAST CUSTOM_TXT_CDS <CON_TC_SNM81>
J 0
(-2050 4525);
PAINT ORANGE (-2050 4525);
FORCEPROP 2 LAST CUSTOM_TXT_CDS <CON_TC_SNM82>
J 0
(-2050 4425);
PAINT ORANGE (-2050 4425);
FORCEPROP 2 LAST CUSTOM_TXT_CDS <CON_TC_SNM83>
J 0
(-2050 4325);
PAINT ORANGE (-2050 4325);
FORCEPROP 2 LAST CUSTOM_TXT_CDS <CON_TC_SNM85>
J 0
(-2050 4125);
PAINT ORANGE (-2050 4125);
FORCEPROP 2 LAST CUSTOM_TXT_CDS <CON_TC_SNM87>
J 0
(-2050 3925);
PAINT ORANGE (-2050 3925);
FORCEPROP 2 LAST CUSTOM_TXT_CDS <CON_TC_SNM88>
J 0
(-2050 3825);
PAINT ORANGE (-2050 3825);
FORCEPROP 2 LAST CUSTOM_TXT_CDS <CON_TC_SNM89>
J 0
(-2050 3725);
PAINT ORANGE (-2050 3725);
FORCEPROP 2 LAST CUSTOM_TXT_CDS <CON_TC_SNM93>
J 0
(-2050 3325);
PAINT ORANGE (-2050 3325);
FORCEPROP 2 LAST CUSTOM_TXT_CDS <CON_TC_SNM96>
J 0
(-2050 3025);
PAINT ORANGE (-2050 3025);
FORCEPROP 2 LAST CUSTOM_TXT_CDS <CON_TC_SNM97>
J 0
(-2050 2925);
PAINT ORANGE (-2050 2925);
FORCEPROP 2 LAST CUSTOM_TXT_CDS <CON_TC_SNM100>
J 0
(-2050 2625);
PAINT ORANGE (-2050 2625);
FORCEPROP 2 LAST CUSTOM_TXT_CDS <CON_TC_SNM101>
J 0
(-2050 2525);
PAINT ORANGE (-2050 2525);
FORCEPROP 2 LAST CUSTOM_TXT_CDS <CON_TC_SNM102>
J 0
(-2050 2425);
PAINT ORANGE (-2050 2425);
FORCEPROP 2 LAST CUSTOM_TXT_CDS <CON_TC_SNM103>
J 0
(-2050 2325);
PAINT ORANGE (-2050 2325);
FORCEPROP 2 LAST CUSTOM_TXT_CDS <CON_TC_SNM106>
J 0
(-2050 2025);
PAINT ORANGE (-2050 2025);
FORCEPROP 2 LAST CUSTOM_TXT_CDS <CON_TC_SNM107>
J 0
(-2050 1925);
PAINT ORANGE (-2050 1925);
FORCEPROP 2 LAST CUSTOM_TXT_CDS <CON_TC_SNM108>
J 0
(-2050 1825);
PAINT ORANGE (-2050 1825);
FORCEPROP 2 LAST CUSTOM_TXT_CDS <CON_TC_SNM110>
J 0
(-2050 1625);
PAINT ORANGE (-2050 1625);
FORCEPROP 2 LAST CUSTOM_TXT_CDS <CON_TC_SNM112>
J 0
(-2050 1425);
PAINT ORANGE (-2050 1425);
FORCEPROP 2 LAST CUSTOM_TXT_CDS <CON_TC_SNM114>
J 0
(-2050 1225);
PAINT ORANGE (-2050 1225);
FORCEPROP 2 LAST CUSTOM_TXT_CDS <CON_TC_SNM115>
J 0
(-2050 1125);
PAINT ORANGE (-2050 1125);
FORCEPROP 2 LAST CUSTOM_TXT_CDS <CON_TC_SNO20>
J 2
(-7150 2625);
PAINT ORANGE (-7150 2625);
FORCEPROP 2 LAST CUSTOM_TXT_CDS <CON_TC_SNO21>
J 2
(-7150 2525);
PAINT ORANGE (-7150 2525);
FORCEPROP 2 LAST CUSTOM_TXT_CDS <CON_TC_SNO22>
J 2
(-7150 2425);
PAINT ORANGE (-7150 2425);
FORCEPROP 2 LAST CUSTOM_TXT_CDS <CON_TC_SNO23>
J 2
(-7150 2325);
PAINT ORANGE (-7150 2325);
FORCEPROP 2 LAST CUSTOM_TXT_CDS <CON_TC_SNO24>
J 2
(-7150 2225);
PAINT ORANGE (-7150 2225);
FORCEPROP 2 LAST CUSTOM_TXT_CDS <CON_TC_SNO25>
J 2
(-7150 2125);
PAINT ORANGE (-7150 2125);
FORCEPROP 2 LAST CUSTOM_TXT_CDS <CON_TC_SNO26>
J 2
(-7150 2025);
PAINT ORANGE (-7150 2025);
FORCEPROP 2 LAST CUSTOM_TXT_CDS <CON_TC_SNO27>
J 2
(-7150 1925);
PAINT ORANGE (-7150 1925);
FORCEPROP 2 LAST CUSTOM_TXT_CDS <CON_TC_SNO28>
J 2
(-7150 1825);
PAINT ORANGE (-7150 1825);
FORCEPROP 2 LAST CUSTOM_TXT_CDS <CON_TC_SNO29>
J 2
(-7150 1725);
PAINT ORANGE (-7150 1725);
FORCEPROP 2 LAST CUSTOM_TXT_CDS <CON_TC_SNO30>
J 2
(-7150 1625);
PAINT ORANGE (-7150 1625);
FORCEPROP 2 LAST CUSTOM_TXT_CDS <CON_TC_SNO31>
J 2
(-7150 1525);
PAINT ORANGE (-7150 1525);
FORCEPROP 2 LAST CUSTOM_TXT_CDS <CON_TC_SNO32>
J 2
(-7150 1425);
PAINT ORANGE (-7150 1425);
FORCEPROP 2 LAST CUSTOM_TXT_CDS <CON_TC_SNO33>
J 2
(-7150 1325);
PAINT ORANGE (-7150 1325);
FORCEPROP 2 LAST CUSTOM_TXT_CDS <CON_TC_SNO34>
J 2
(-7150 1225);
PAINT ORANGE (-7150 1225);
FORCEPROP 2 LAST CUSTOM_TXT_CDS <CON_TC_SNO35>
J 2
(-7150 1125);
PAINT ORANGE (-7150 1125);
FORCEPROP 2 LAST CUSTOM_TXT_CDS <CON_TC_SNO36>
J 2
(-7150 1025);
PAINT ORANGE (-7150 1025);
FORCEPROP 2 LAST CUSTOM_TXT_CDS <CON_TC_SNO37>
J 2
(-7150 925);
PAINT ORANGE (-7150 925);
FORCEPROP 2 LAST CUSTOM_TXT_CDS <CON_TC_SNO38>
J 2
(-7150 825);
PAINT ORANGE (-7150 825);
FORCEPROP 2 LAST CUSTOM_TXT_CDS <CON_TC_SNO39>
J 2
(-7150 725);
PAINT ORANGE (-7150 725);
FORCEPROP 2 LAST CUSTOM_TXT_CDS <CON_TC_SNO40>
J 2
(-7150 625);
PAINT ORANGE (-7150 625);
FORCEPROP 2 LAST CUSTOM_TXT_CDS <CON_TC_SNO41>
J 2
(-4650 4525);
PAINT ORANGE (-4650 4525);
FORCEPROP 2 LAST CUSTOM_TXT_CDS <CON_TC_SNO42>
J 2
(-4650 4425);
PAINT ORANGE (-4650 4425);
FORCEPROP 2 LAST CUSTOM_TXT_CDS <CON_TC_SNO43>
J 2
(-4650 4325);
PAINT ORANGE (-4650 4325);
FORCEPROP 2 LAST CUSTOM_TXT_CDS <CON_TC_SNO44>
J 2
(-4650 4225);
PAINT ORANGE (-4650 4225);
FORCEPROP 2 LAST CUSTOM_TXT_CDS <CON_TC_SNO45>
J 2
(-4650 4125);
PAINT ORANGE (-4650 4125);
FORCEPROP 2 LAST CUSTOM_TXT_CDS <CON_TC_SNO46>
J 2
(-4650 4025);
PAINT ORANGE (-4650 4025);
FORCEPROP 2 LAST CUSTOM_TXT_CDS <CON_TC_SNO47>
J 2
(-4650 3925);
PAINT ORANGE (-4650 3925);
FORCEPROP 2 LAST CUSTOM_TXT_CDS <CON_TC_SNO49>
J 2
(-4650 3725);
PAINT ORANGE (-4650 3725);
FORCEPROP 2 LAST CUSTOM_TXT_CDS <CON_TC_SNO50>
J 2
(-4650 3625);
PAINT ORANGE (-4650 3625);
FORCEPROP 2 LAST CUSTOM_TXT_CDS <CON_TC_SNO51>
J 2
(-4650 3525);
PAINT ORANGE (-4650 3525);
FORCEPROP 2 LAST CUSTOM_TXT_CDS <CON_TC_SNO53>
J 2
(-4650 3325);
PAINT ORANGE (-4650 3325);
FORCEPROP 2 LAST CUSTOM_TXT_CDS <CON_TC_SNO54>
J 2
(-4650 3225);
PAINT ORANGE (-4650 3225);
FORCEPROP 2 LAST CUSTOM_TXT_CDS <CON_TC_SNO55>
J 2
(-4650 3125);
PAINT ORANGE (-4650 3125);
FORCEPROP 2 LAST CUSTOM_TXT_CDS <CON_TC_SNO56>
J 2
(-4650 3025);
PAINT ORANGE (-4650 3025);
FORCEPROP 2 LAST CUSTOM_TXT_CDS <CON_TC_SNO57>
J 2
(-4650 2925);
PAINT ORANGE (-4650 2925);
FORCEPROP 2 LAST CUSTOM_TXT_CDS <CON_TC_SNO58>
J 2
(-4650 2825);
PAINT ORANGE (-4650 2825);
FORCEPROP 2 LAST CUSTOM_TXT_CDS <CON_TC_SNO59>
J 2
(-4650 2725);
PAINT ORANGE (-4650 2725);
FORCEPROP 2 LAST CUSTOM_TXT_CDS <CON_TC_SNO60>
J 2
(-4650 2625);
PAINT ORANGE (-4650 2625);
FORCEPROP 2 LAST CUSTOM_TXT_CDS <CON_TC_SNO61>
J 2
(-4650 2525);
PAINT ORANGE (-4650 2525);
FORCEPROP 2 LAST CUSTOM_TXT_CDS <CON_TC_SNO62>
J 2
(-4650 2425);
PAINT ORANGE (-4650 2425);
FORCEPROP 2 LAST CUSTOM_TXT_CDS <CON_TC_SNO63>
J 2
(-4650 2325);
PAINT ORANGE (-4650 2325);
FORCEPROP 2 LAST CUSTOM_TXT_CDS <CON_TC_SNO64>
J 2
(-4650 2225);
PAINT ORANGE (-4650 2225);
FORCEPROP 2 LAST CUSTOM_TXT_CDS <CON_TC_SNO65>
J 2
(-4650 2125);
PAINT ORANGE (-4650 2125);
FORCEPROP 2 LAST CUSTOM_TXT_CDS <CON_TC_SNO66>
J 2
(-4650 2025);
PAINT ORANGE (-4650 2025);
FORCEPROP 2 LAST CUSTOM_TXT_CDS <CON_TC_SNO67>
J 2
(-4650 1925);
PAINT ORANGE (-4650 1925);
FORCEPROP 2 LAST CUSTOM_TXT_CDS <CON_TC_SNO69>
J 2
(-4650 1725);
PAINT ORANGE (-4650 1725);
FORCEPROP 2 LAST CUSTOM_TXT_CDS <CON_TC_SNO70>
J 2
(-4650 1625);
PAINT ORANGE (-4650 1625);
FORCEPROP 2 LAST CUSTOM_TXT_CDS <CON_TC_SNO72>
J 2
(-4650 1425);
PAINT ORANGE (-4650 1425);
FORCEPROP 2 LAST CUSTOM_TXT_CDS <CON_TC_SNO73>
J 2
(-4650 1325);
PAINT ORANGE (-4650 1325);
FORCEPROP 2 LAST CUSTOM_TXT_CDS <CON_TC_SNO74>
J 2
(-4650 1225);
PAINT ORANGE (-4650 1225);
FORCEPROP 2 LAST CUSTOM_TXT_CDS <CON_TC_SNO75>
J 2
(-4650 1125);
PAINT ORANGE (-4650 1125);
FORCEPROP 2 LAST CUSTOM_TXT_CDS <CON_TC_SNO76>
J 2
(-4650 1025);
PAINT ORANGE (-4650 1025);
FORCEPROP 2 LAST CUSTOM_TXT_CDS <CON_TC_SNO77>
J 2
(-4650 925);
PAINT ORANGE (-4650 925);
FORCEPROP 2 LAST CUSTOM_TXT_CDS <CON_TC_SNO78>
J 2
(-4650 825);
PAINT ORANGE (-4650 825);
FORCEPROP 2 LAST CUSTOM_TXT_CDS <CON_TC_SNO79>
J 2
(-4650 725);
PAINT ORANGE (-4650 725);
FORCEPROP 2 LAST CUSTOM_TXT_CDS <CON_TC_SNO80>
J 2
(-4650 625);
PAINT ORANGE (-4650 625);
FORCEPROP 2 LAST CUSTOM_TXT_CDS <CON_TC_SNO81>
J 2
(-2150 4525);
PAINT ORANGE (-2150 4525);
FORCEPROP 2 LAST CUSTOM_TXT_CDS <CON_TC_SNO82>
J 2
(-2150 4425);
PAINT ORANGE (-2150 4425);
FORCEPROP 2 LAST CUSTOM_TXT_CDS <CON_TC_SNO83>
J 2
(-2150 4325);
PAINT ORANGE (-2150 4325);
FORCEPROP 2 LAST CUSTOM_TXT_CDS <CON_TC_SNO84>
J 2
(-2150 4225);
PAINT ORANGE (-2150 4225);
FORCEPROP 2 LAST CUSTOM_TXT_CDS <CON_TC_SNO85>
J 2
(-2150 4125);
PAINT ORANGE (-2150 4125);
FORCEPROP 2 LAST CUSTOM_TXT_CDS <CON_TC_SNO86>
J 2
(-2150 4025);
PAINT ORANGE (-2150 4025);
FORCEPROP 2 LAST CUSTOM_TXT_CDS <CON_TC_SNO87>
J 2
(-2150 3925);
PAINT ORANGE (-2150 3925);
FORCEPROP 2 LAST CUSTOM_TXT_CDS <CON_TC_SNO88>
J 2
(-2150 3825);
PAINT ORANGE (-2150 3825);
FORCEPROP 2 LAST CUSTOM_TXT_CDS <CON_TC_SNO89>
J 2
(-2150 3725);
PAINT ORANGE (-2150 3725);
FORCEPROP 2 LAST CUSTOM_TXT_CDS <CON_TC_SNO90>
J 2
(-2150 3625);
PAINT ORANGE (-2150 3625);
FORCEPROP 2 LAST CUSTOM_TXT_CDS <CON_TC_SNO91>
J 2
(-2150 3525);
PAINT ORANGE (-2150 3525);
FORCEPROP 2 LAST CUSTOM_TXT_CDS <CON_TC_SNO92>
J 2
(-2150 3425);
PAINT ORANGE (-2150 3425);
FORCEPROP 2 LAST CUSTOM_TXT_CDS <CON_TC_SNO93>
J 2
(-2150 3325);
PAINT ORANGE (-2150 3325);
FORCEPROP 2 LAST CUSTOM_TXT_CDS <CON_TC_SNO94>
J 2
(-2150 3225);
PAINT ORANGE (-2150 3225);
FORCEPROP 2 LAST CUSTOM_TXT_CDS <CON_TC_SNO95>
J 2
(-2150 3125);
PAINT ORANGE (-2150 3125);
FORCEPROP 2 LAST CUSTOM_TXT_CDS <CON_TC_SNO96>
J 2
(-2150 3025);
PAINT ORANGE (-2150 3025);
FORCEPROP 2 LAST CUSTOM_TXT_CDS <CON_TC_SNO97>
J 2
(-2150 2925);
PAINT ORANGE (-2150 2925);
FORCEPROP 2 LAST CUSTOM_TXT_CDS <CON_TC_SNO98>
J 2
(-2150 2825);
PAINT ORANGE (-2150 2825);
FORCEPROP 2 LAST CUSTOM_TXT_CDS <CON_TC_SNO99>
J 2
(-2150 2725);
PAINT ORANGE (-2150 2725);
FORCEPROP 2 LAST CUSTOM_TXT_CDS <CON_TC_SNO100>
J 2
(-2150 2625);
PAINT ORANGE (-2150 2625);
FORCEPROP 2 LAST CUSTOM_TXT_CDS <CON_TC_SNO101>
J 2
(-2150 2525);
PAINT ORANGE (-2150 2525);
FORCEPROP 2 LAST CUSTOM_TXT_CDS <CON_TC_SNO102>
J 2
(-2150 2425);
PAINT ORANGE (-2150 2425);
FORCEPROP 2 LAST CUSTOM_TXT_CDS <CON_TC_SNO103>
J 2
(-2150 2325);
PAINT ORANGE (-2150 2325);
FORCEPROP 2 LAST CUSTOM_TXT_CDS <CON_TC_SNO104>
J 2
(-2150 2225);
PAINT ORANGE (-2150 2225);
FORCEPROP 2 LAST CUSTOM_TXT_CDS <CON_TC_SNO105>
J 2
(-2150 2125);
PAINT ORANGE (-2150 2125);
FORCEPROP 2 LAST CUSTOM_TXT_CDS <CON_TC_SNO107>
J 2
(-2150 1925);
PAINT ORANGE (-2150 1925);
FORCEPROP 2 LAST CUSTOM_TXT_CDS <CON_TC_SNO110>
J 2
(-2150 1625);
PAINT ORANGE (-2150 1625);
FORCEPROP 2 LAST CUSTOM_TXT_CDS <CON_TC_SNO111>
J 2
(-2150 1525);
PAINT ORANGE (-2150 1525);
FORCEPROP 2 LAST CUSTOM_TXT_CDS <CON_TC_SNO112>
J 2
(-2150 1425);
PAINT ORANGE (-2150 1425);
FORCEPROP 2 LAST CUSTOM_TXT_CDS <CON_TC_SNO113>
J 2
(-2150 1325);
PAINT ORANGE (-2150 1325);
FORCEPROP 2 LAST CUSTOM_TXT_CDS <CON_TC_SNO114>
J 2
(-2150 1225);
PAINT ORANGE (-2150 1225);
FORCEPROP 2 LAST CUSTOM_TXT_CDS <CON_TC_SNO115>
J 2
(-2150 1125);
PAINT ORANGE (-2150 1125);
FORCEPROP 2 LAST CUSTOM_TXT_CDS <CON_TC_SNO116>
J 2
(-2150 1025);
PAINT ORANGE (-2150 1025);
FORCEPROP 2 LAST CUSTOM_TXT_CDS <CON_TC_SNO117>
J 2
(-2150 925);
PAINT ORANGE (-2150 925);
FORCEPROP 2 LAST CUSTOM_TXT_CDS <CON_TC_SNO119>
J 2
(-2150 725);
PAINT ORANGE (-2150 725);
FORCEPROP 2 LAST CUSTOM_TXT_CDS <CON_TC_SNM43>
J 0
(-4550 4325);
PAINT ORANGE (-4550 4325);
FORCEPROP 2 LAST CUSTOM_TXT_CDS <CON_TC_SNM42>
J 0
(-4550 4425);
PAINT ORANGE (-4550 4425);
FORCEPROP 2 LAST CUSTOM_TXT_CDS <CON_TC_SNO106>
J 2
(-2150 2025);
PAINT ORANGE (-2150 2025);
FORCEPROP 2 LAST CUSTOM_TXT_CDS <CON_TC_SNO108>
J 2
(-2150 1825);
PAINT ORANGE (-2150 1825);
FORCEPROP 2 LAST CUSTOM_TXT_CDS <CON_TC_SNO109>
J 2
(-2150 1725);
PAINT ORANGE (-2150 1725);
FORCEPROP 2 LAST CUSTOM_TXT_CDS <CON_TC_SNM111>
J 0
(-2050 1525);
PAINT ORANGE (-2050 1525);
FORCEPROP 2 LAST CUSTOM_TXT_CDS <CON_TC_SNM113>
J 0
(-2050 1325);
PAINT ORANGE (-2050 1325);
FORCEPROP 2 LAST CUSTOM_TXT_CDS <CON_TC_SNM116>
J 0
(-2050 1025);
PAINT ORANGE (-2050 1025);
FORCEPROP 2 LAST CUSTOM_TXT_CDS <CON_TC_SNM78>
J 0
(-4550 825);
PAINT ORANGE (-4550 825);
FORCEPROP 2 LAST CUSTOM_TXT_CDS <CON_TC_SNM32>
J 0
(-7050 1425);
PAINT ORANGE (-7050 1425);
FORCEPROP 2 LAST CUSTOM_TXT_CDS <CON_TC_SNM79>
J 0
(-4550 725);
PAINT ORANGE (-4550 725);
FORCEPROP 1 LAST SCH_TITLE INDEX (1 OF 3)
J 0
(-7950 50);
DISPLAY 1.212766 (-7950 50);
PAINT ORANGE (-7950 50);
FORCEPROP 1 LAST COMMENT_BODY TRUE
J 0
(12 12);
DISPLAY 0.468085 (12 12);
PAINT GREEN (12 12);
DISPLAY INVISIBLE (12 12);
FORCEPROP 1 LAST TOC_SYMBOL TRUE
J 0
(-7950 5050);
PAINT ORANGE (-7950 5050);
DISPLAY INVISIBLE (-7950 5050);
FORCEPROP 2 LAST CDS_LIB mstr_symbols
J 0
(0 0);
PAINT ORANGE (0 0);
DISPLAY INVISIBLE (0 0);
FORCEPROP 2 LAST PAGE_BORDER TRUE
J 0
(-7890 5250);
DISPLAY 0.638298 (-7890 5250);
PAINT PINK (-7890 5250);
DISPLAY INVISIBLE (-7890 5250);
FORCEPROP 2 LAST CDS_XR_PAGE_TITLE CR-2 : @BASEBOARD_FAB2_LIB.BASEBOARD_FAB2(SCH_1):PAGE2
J 0
(-7890 5250);
DISPLAY 0.638298 (-7890 5250);
PAINT PINK (-7890 5250);
DISPLAY INVISIBLE (-7890 5250);
QUIT
